# SCM (Grand Teton) — schematic netlist excerpt (pin names and nets, part order shuffled) for the footprints in the layout excerpt that follows; sources: Cadence DE-HDL packaged netlist, KiCad conversion of 12092022_DA0F0TMDCD0_F0T_Management_Board_D_brd_V3_OCP.brd

C2  Q_CAP  1UF 25V 10% X6S  pkg C0402  page 20 : A = P1V2_AUX ; B = GND
C133  Q_CAP  0.01UF 50V 10% X7R  pkg C0402  page 17 : A = GND ; B = A_BMC_ADCVREFN1

(kicad_pcb
	(version 20260206)
	(generator "pcbnew")
	(generator_version "10.0")
	(general
		(thickness 1.6)
		(legacy_teardrops no)
	)
	(paper "A4")
	(title_block
		(title "12092022_DA0F0TMDCD0_F0T_Management_Board_D_brd_V3_OCP.brd")
		(comment 1 "Grand Teton / footprints 737-738 of 1440")
	)
	(layers
		(0 "F.Cu" signal "TOP")
		(4 "In1.Cu" signal "GND")
		(6 "In2.Cu" signal "IN1")
		(8 "In3.Cu" signal "GND1")
		(10 "In4.Cu" signal "IN2")
		(12 "In5.Cu" signal "VCC")
		(14 "In6.Cu" signal "VCC1")
		(16 "In7.Cu" signal "IN3")
		(18 "In8.Cu" signal "GND2")
		(20 "In9.Cu" signal "IN4")
		(22 "In10.Cu" signal "GND3")
		(2 "B.Cu" signal "BOTTOM")
		(9 "F.Adhes" user "F.Adhesive")
		(11 "B.Adhes" user "B.Adhesive")
		(13 "F.Paste" user "Package Geometry/Pastemask Top")
		(15 "B.Paste" user "Package Geometry/Pastemask Bottom")
		(5 "F.SilkS" user "Ref Des/Silkscreen Top")
		(7 "B.SilkS" user "Ref Des/Silkscreen Bottom")
		(1 "F.Mask" user "Board Geometry/Soldermask Top")
		(3 "B.Mask" user "Board Geometry/Soldermask Bottom")
		(17 "Dwgs.User" user "User.Drawings")
		(19 "Cmts.User" user "User.Comments")
		(21 "Eco1.User" user "User.Eco1")
		(23 "Eco2.User" user "User.Eco2")
		(25 "Edge.Cuts" user "Board Geometry/Outline")
		(27 "Margin" user)
		(31 "F.CrtYd" user "Package Geometry/Place Bound Top")
		(29 "B.CrtYd" user "Package Geometry/Place Bound Bottom")
		(35 "F.Fab" user "Ref Des/Assembly Top")
		(33 "B.Fab" user "Ref Des/Assembly Bottom")
	)
	(footprint ""
		(layer "B.Cu")
		(at 80.512666 -49.261776 90)
		(property "Reference" "C2"
			(at 0 0 90)
			(layer "B.SilkS")
			(hide yes)
			(effects
				(font
					(size 1.27 1.27)
				)
				(justify mirror)
			)
		)
		(property "Value" ""
			(at 0 0 90)
			(layer "B.Fab")
			(effects
				(font
					(size 1.27 1.27)
				)
				(justify mirror)
			)
		)
		(duplicate_pad_numbers_are_jumpers no)
		(fp_line
			(start 0.7874 -0.4064)
			(end -0.7874 -0.4064)
			(stroke
				(width 0.1524)
				(type default)
			)
			(layer "B.SilkS")
		)
		(fp_line
			(start -0.7874 -0.4064)
			(end -0.7874 0.4064)
			(stroke
				(width 0.1524)
				(type default)
			)
			(layer "B.SilkS")
		)
		(fp_line
			(start 0.7874 0.4064)
			(end 0.7874 -0.4064)
			(stroke
				(width 0.1524)
				(type default)
			)
			(layer "B.SilkS")
		)
		(fp_line
			(start -0.7874 0.4064)
			(end 0.7874 0.4064)
			(stroke
				(width 0.1524)
				(type default)
			)
			(layer "B.SilkS")
		)
		(fp_line
			(start 0.67945 -0.305054)
			(end 0.12065 -0.305054)
			(stroke
				(width 0.1)
				(type default)
			)
			(layer "B.Fab")
		)
		(fp_line
			(start 0.12065 -0.305054)
			(end 0.12065 -0.2794)
			(stroke
				(width 0.1)
				(type default)
			)
			(layer "B.Fab")
		)
		(fp_line
			(start -0.12065 -0.3048)
			(end -0.67945 -0.3048)
			(stroke
				(width 0.1)
				(type default)
			)
			(layer "B.Fab")
		)
		(fp_line
			(start -0.67945 -0.3048)
			(end -0.67945 0.3048)
			(stroke
				(width 0.1)
				(type default)
			)
			(layer "B.Fab")
		)
		(fp_line
			(start 0.12065 -0.2794)
			(end -0.12065 -0.2794)
			(stroke
				(width 0.1)
				(type default)
			)
			(layer "B.Fab")
		)
		(fp_line
			(start -0.12065 -0.2794)
			(end -0.12065 -0.3048)
			(stroke
				(width 0.1)
				(type default)
			)
			(layer "B.Fab")
		)
		(fp_line
			(start 0.12065 0.2794)
			(end 0.12065 0.3048)
			(stroke
				(width 0.1)
				(type default)
			)
			(layer "B.Fab")
		)
		(fp_line
			(start -0.120396 0.2794)
			(end 0.12065 0.2794)
			(stroke
				(width 0.1)
				(type default)
			)
			(layer "B.Fab")
		)
		(fp_line
			(start 0.67945 0.3048)
			(end 0.67945 -0.305054)
			(stroke
				(width 0.1)
				(type default)
			)
			(layer "B.Fab")
		)
		(fp_line
			(start 0.12065 0.3048)
			(end 0.67945 0.3048)
			(stroke
				(width 0.1)
				(type default)
			)
			(layer "B.Fab")
		)
		(fp_line
			(start -0.120396 0.3048)
			(end -0.120396 0.2794)
			(stroke
				(width 0.1)
				(type default)
			)
			(layer "B.Fab")
		)
		(fp_line
			(start -0.67945 0.3048)
			(end -0.120396 0.3048)
			(stroke
				(width 0.1)
				(type default)
			)
			(layer "B.Fab")
		)
		(pad "1" smd circle
			(at 0.40005 0 270)
			(size 0 0)
			(layers "B.Cu" "B.Mask" "B.Paste")
			(net "P1V2_AUX")
		)
		(pad "2" smd circle
			(at -0.40005 0 270)
			(size 0 0)
			(layers "B.Cu" "B.Mask" "B.Paste")
			(net "GND")
		)
	)
	(footprint ""
		(layer "B.Cu")
		(at 50.54346 -61.852048 90)
		(property "Reference" "C133"
			(at 0 0 90)
			(layer "B.SilkS")
			(hide yes)
			(effects
				(font
					(size 1.27 1.27)
				)
				(justify mirror)
			)
		)
		(property "Value" ""
			(at 0 0 90)
			(layer "B.Fab")
			(effects
				(font
					(size 1.27 1.27)
				)
				(justify mirror)
			)
		)
		(duplicate_pad_numbers_are_jumpers no)
		(fp_line
			(start 0.7874 -0.4064)
			(end -0.7874 -0.4064)
			(stroke
				(width 0.1524)
				(type default)
			)
			(layer "B.SilkS")
		)
		(fp_line
			(start -0.7874 -0.4064)
			(end -0.7874 0.4064)
			(stroke
				(width 0.1524)
				(type default)
			)
			(layer "B.SilkS")
		)
		(fp_line
			(start 0.7874 0.4064)
			(end 0.7874 -0.4064)
			(stroke
				(width 0.1524)
				(type default)
			)
			(layer "B.SilkS")
		)
		(fp_line
			(start -0.7874 0.4064)
			(end 0.7874 0.4064)
			(stroke
				(width 0.1524)
				(type default)
			)
			(layer "B.SilkS")
		)
		(fp_line
			(start 0.67945 -0.305054)
			(end 0.12065 -0.305054)
			(stroke
				(width 0.1)
				(type default)
			)
			(layer "B.Fab")
		)
		(fp_line
			(start 0.12065 -0.305054)
			(end 0.12065 -0.2794)
			(stroke
				(width 0.1)
				(type default)
			)
			(layer "B.Fab")
		)
		(fp_line
			(start -0.12065 -0.3048)
			(end -0.67945 -0.3048)
			(stroke
				(width 0.1)
				(type default)
			)
			(layer "B.Fab")
		)
		(fp_line
			(start -0.67945 -0.3048)
			(end -0.67945 0.3048)
			(stroke
				(width 0.1)
				(type default)
			)
			(layer "B.Fab")
		)
		(fp_line
			(start 0.12065 -0.2794)
			(end -0.12065 -0.2794)
			(stroke
				(width 0.1)
				(type default)
			)
			(layer "B.Fab")
		)
		(fp_line
			(start -0.12065 -0.2794)
			(end -0.12065 -0.3048)
			(stroke
				(width 0.1)
				(type default)
			)
			(layer "B.Fab")
		)
		(fp_line
			(start 0.12065 0.2794)
			(end 0.12065 0.3048)
			(stroke
				(width 0.1)
				(type default)
			)
			(layer "B.Fab")
		)
		(fp_line
			(start -0.120396 0.2794)
			(end 0.12065 0.2794)
			(stroke
				(width 0.1)
				(type default)
			)
			(layer "B.Fab")
		)
		(fp_line
			(start 0.67945 0.3048)
			(end 0.67945 -0.305054)
			(stroke
				(width 0.1)
				(type default)
			)
			(layer "B.Fab")
		)
		(fp_line
			(start 0.12065 0.3048)
			(end 0.67945 0.3048)
			(stroke
				(width 0.1)
				(type default)
			)
			(layer "B.Fab")
		)
		(fp_line
			(start -0.120396 0.3048)
			(end -0.120396 0.2794)
			(stroke
				(width 0.1)
				(type default)
			)
			(layer "B.Fab")
		)
		(fp_line
			(start -0.67945 0.3048)
			(end -0.120396 0.3048)
			(stroke
				(width 0.1)
				(type default)
			)
			(layer "B.Fab")
		)
		(pad "1" smd circle
			(at 0.40005 0 270)
			(size 0 0)
			(layers "B.Cu" "B.Mask" "B.Paste")
			(net "GND")
		)
		(pad "2" smd circle
			(at -0.40005 0 270)
			(size 0 0)
			(layers "B.Cu" "B.Mask" "B.Paste")
			(net "A_BMC_ADCVREFN1")
		)
	)
)
